FILE_TYPE = MACRO_DRAWING;
SET COLOR_WIRE YELLOW;
SET COLOR_PROP MONO;
SET COLOR_DOT WHITE;
SET COLOR_ARC YELLOW;
SET COLOR_BODY GREEN;
SET COLOR_NOTE MONO;
SET PROP_DISPLAY VALUE;
SET PAGE_NUMBER P136;
FORCEADD RES..2
(-2250 4800);
FORCEPROP 1 LASTPIN (-2250 4900) $PN 1
J 0
(-2245 4862);
DISPLAY 0.617021 (-2245 4862);
PAINT ORANGE (-2245 4862);
FORCEPROP 1 LASTPIN (-2250 4700) $PN 2
J 0
(-2245 4710);
DISPLAY 0.617021 (-2245 4710);
PAINT ORANGE (-2245 4710);
FORCEPROP 1 LAST WATTAGE 1/16W
J 0
(-2210 4775);
DISPLAY 0.617021 (-2210 4775);
PAINT SKYBLUE (-2210 4775);
FORCEPROP 1 LAST MATERIAL CHIP
J 0
(-2210 4725);
DISPLAY 0.617021 (-2210 4725);
PAINT SKYBLUE (-2210 4725);
FORCEPROP 1 LAST PACK_TYPE 0402
J 0
(-2210 4625);
DISPLAY 0.617021 (-2210 4625);
PAINT SKYBLUE (-2210 4625);
FORCEPROP 1 LAST TOLERANCE 1%
J 0
(-2205 4825);
DISPLAY 0.617021 (-2205 4825);
PAINT SKYBLUE (-2205 4825);
FORCEPROP 1 LAST VALUE 10.0K
J 0
(-2205 4875);
DISPLAY 0.617021 (-2205 4875);
PAINT SKYBLUE (-2205 4875);
FORCEPROP 1 LAST PART_NUMBER G21796-016
J 0
(-2210 4675);
DISPLAY 0.617021 (-2210 4675);
PAINT BLUE (-2210 4675);
FORCEPROP 1 LAST LOCATION R7G26
J 0
(-2205 4925);
DISPLAY 0.617021 (-2205 4925);
PAINT AQUA (-2205 4925);
FORCEPROP 1 LAST PATH I101
J 0
(-2200 4975);
DISPLAY 0.978723 (-2200 4975);
PAINT WHITE (-2200 4975);
DISPLAY INVISIBLE (-2200 4975);
FORCEPROP 2 LAST SEC 1
J 0
(-2200 5025);
DISPLAY 0.680851 (-2200 5025);
PAINT MONO (-2200 5025);
DISPLAY INVISIBLE (-2200 5025);
FORCEPROP 2 LAST SEC_TYPE 0402
J 0
(-2200 5025);
DISPLAY 1.021277 (-2200 5025);
PAINT ORANGE (-2200 5025);
DISPLAY INVISIBLE (-2200 5025);
FORCEPROP 2 LAST CDS_LIB mstr_discrete
J 0
(-2250 4800);
PAINT ORANGE (-2250 4800);
DISPLAY INVISIBLE (-2250 4800);
FORCEPROP 2 LAST ROOM SB
J 0
(-2200 4975);
PAINT MONO (-2200 4975);
DISPLAY INVISIBLE (-2200 4975);
FORCEADD RES..2
(-2250 3825);
FORCEPROP 1 LASTPIN (-2250 3725) $PN 2
J 0
(-2245 3735);
DISPLAY 0.617021 (-2245 3735);
PAINT ORANGE (-2245 3735);
FORCEPROP 1 LASTPIN (-2250 3925) $PN 1
J 0
(-2245 3887);
DISPLAY 0.617021 (-2245 3887);
PAINT ORANGE (-2245 3887);
FORCEPROP 1 LAST WATTAGE 1/16W
J 0
(-2210 3800);
DISPLAY 0.617021 (-2210 3800);
PAINT SKYBLUE (-2210 3800);
FORCEPROP 1 LAST MATERIAL CHIP
J 0
(-2210 3750);
DISPLAY 0.617021 (-2210 3750);
PAINT SKYBLUE (-2210 3750);
FORCEPROP 1 LAST PACK_TYPE 0402
J 0
(-2210 3650);
DISPLAY 0.617021 (-2210 3650);
PAINT SKYBLUE (-2210 3650);
FORCEPROP 1 LAST TOLERANCE 1%
J 0
(-2205 3850);
DISPLAY 0.617021 (-2205 3850);
PAINT SKYBLUE (-2205 3850);
FORCEPROP 1 LAST VALUE 1.00K
J 0
(-2205 3900);
DISPLAY 0.617021 (-2205 3900);
PAINT SKYBLUE (-2205 3900);
FORCEPROP 1 LAST PART_NUMBER G21796-026
J 0
(-2210 3700);
DISPLAY 0.617021 (-2210 3700);
PAINT BLUE (-2210 3700);
FORCEPROP 1 LAST LOCATION R7G28
J 0
(-2200 3950);
DISPLAY 0.617021 (-2200 3950);
PAINT AQUA (-2200 3950);
FORCEPROP 2 LAST CDS_LIB mstr_discrete
J 0
(-2250 3825);
PAINT ORANGE (-2250 3825);
DISPLAY INVISIBLE (-2250 3825);
FORCEPROP 2 LAST BOM_COST SB
J 0
(-2400 3975);
PAINT ORANGE (-2400 3975);
DISPLAY INVISIBLE (-2400 3975);
FORCEPROP 2 LAST SEC_TYPE 0402
J 0
(-2200 4050);
DISPLAY 1.021277 (-2200 4050);
PAINT ORANGE (-2200 4050);
DISPLAY INVISIBLE (-2200 4050);
FORCEPROP 2 LAST SEC 1
J 0
(-2200 4050);
DISPLAY 0.680851 (-2200 4050);
PAINT MONO (-2200 4050);
DISPLAY INVISIBLE (-2200 4050);
FORCEPROP 1 LAST PATH I102
J 0
(-2200 4000);
DISPLAY 0.978723 (-2200 4000);
PAINT WHITE (-2200 4000);
DISPLAY INVISIBLE (-2200 4000);
FORCEPROP 2 LAST ROOM SB
J 0
(-1675 3925);
PAINT PEACH (-1675 3925);
DISPLAY INVISIBLE (-1675 3925);
FORCEADD GND..1
(-2250 3625);
FORCEPROP 3 LASTPIN (-2250 3675) SIG_NAME GND\g
J 0
(-2240 3685);
DISPLAY 0.659574 (-2240 3685);
PAINT MONO (-2240 3685);
DISPLAY INVISIBLE (-2240 3685);
FORCEPROP 1 LAST PATH I103
J 0
(-2175 3625);
DISPLAY 0.872340 (-2175 3625);
PAINT AQUA (-2175 3625);
DISPLAY INVISIBLE (-2175 3625);
FORCEPROP 1 LAST BODY_TYPE PLUMBING
J 0
(-2295 3582);
DISPLAY 0.340426 (-2295 3582);
PAINT GREEN (-2295 3582);
DISPLAY INVISIBLE (-2295 3582);
FORCEPROP 2 LAST CDS_LIB mstr_symbols
J 0
(-2250 3625);
PAINT ORANGE (-2250 3625);
DISPLAY INVISIBLE (-2250 3625);
FORCEPROP 2 LAST BOM_COST SB
J 0
(-2300 3700);
PAINT MONO (-2300 3700);
DISPLAY INVISIBLE (-2300 3700);
FORCEPROP 1 LAST SIZE 1B
J 0
(-2175 3575);
DISPLAY 1.468085 (-2175 3575);
PAINT GREEN (-2175 3575);
DISPLAY INVISIBLE (-2175 3575);
FORCEPROP 1 LAST HDL_POWER GND
J 0
(-2250 3775);
DISPLAY 1.468085 (-2250 3775);
PAINT GREEN (-2250 3775);
DISPLAY INVISIBLE (-2250 3775);
FORCEPROP 1 LAST VOLTAGE 0
J 0
(-2250 3625);
PAINT SKYBLUE (-2250 3625);
DISPLAY INVISIBLE (-2250 3625);
FORCEADD P3V3_STBY..1
(-2250 5025);
FORCEPROP 3 LASTPIN (-2250 4975) SIG_NAME P3V3_STBY\g
J 0
(-2240 4985);
DISPLAY 0.659574 (-2240 4985);
PAINT MONO (-2240 4985);
DISPLAY INVISIBLE (-2240 4985);
FORCEPROP 1 LAST SIZE 1B
J 0
(-2205 5047);
DISPLAY 0.340426 (-2205 5047);
PAINT GREEN (-2205 5047);
DISPLAY INVISIBLE (-2205 5047);
FORCEPROP 2 LAST CDS_LIB mstr_symbols
J 0
(-2250 5025);
PAINT MONO (-2250 5025);
DISPLAY INVISIBLE (-2250 5025);
FORCEPROP 1 LAST BODY_TYPE PLUMBING
J 0
(-2295 4982);
DISPLAY 0.340426 (-2295 4982);
PAINT GREEN (-2295 4982);
DISPLAY INVISIBLE (-2295 4982);
FORCEPROP 1 LAST PATH I124
J 0
(-2205 5027);
DISPLAY 0.340426 (-2205 5027);
PAINT GREEN (-2205 5027);
DISPLAY INVISIBLE (-2205 5027);
FORCEPROP 1 LAST HDL_POWER P3V3_STBY
J 0
(-2550 4900);
DISPLAY 0.872340 (-2550 4900);
PAINT ORANGE (-2550 4900);
DISPLAY INVISIBLE (-2550 4900);
FORCEPROP 1 LAST VOLTAGE 3.3V
J 0
(-2295 4982);
DISPLAY 0.340426 (-2295 4982);
PAINT SKYBLUE (-2295 4982);
DISPLAY INVISIBLE (-2295 4982);
FORCEADD OFFPAGE..2
(1700 2300);
FORCEPROP 2 LAST $XR0 119 
J 0
(1889 2300);
DISPLAY 0.638298 (1889 2300);
PAINT MONO (1889 2300);
FORCEPROP 2 LAST $XR1 175 
J 0
(2009 2300);
DISPLAY 0.638298 (2009 2300);
PAINT MONO (2009 2300);
FORCEPROP 2 LAST PATH I125
J 0
(2025 2350);
DISPLAY 1.021277 (2025 2350);
PAINT ORANGE (2025 2350);
DISPLAY INVISIBLE (2025 2350);
FORCEPROP 1 LAST COMMENT_BODY TRUE
J 0
(1655 2205);
DISPLAY 0.978723 (1655 2205);
PAINT GREEN (1655 2205);
DISPLAY INVISIBLE (1655 2205);
FORCEPROP 1 LAST OFFPAGE TRUE
J 0
(2025 2175);
PAINT GREEN (2025 2175);
DISPLAY INVISIBLE (2025 2175);
FORCEPROP 2 LAST BOM_COST SB
J 0
(1900 2350);
PAINT ORANGE (1900 2350);
DISPLAY INVISIBLE (1900 2350);
FORCEPROP 2 LAST CDS_LIB mstr_standard
J 0
(1700 2300);
PAINT MONO (1700 2300);
DISPLAY INVISIBLE (1700 2300);
FORCEPROP 2 LAST ROOM WBG_HEADERS_BIOS
J 0
(1475 2375);
PAINT ORANGE (1475 2375);
DISPLAY INVISIBLE (1475 2375);
FORCEADD RES..1
(1000 2300);
FORCEPROP 1 LASTPIN (900 2300) $PN 1
J 0
(912 2312);
DISPLAY 0.617021 (912 2312);
PAINT ORANGE (912 2312);
FORCEPROP 1 LASTPIN (1100 2300) $PN 2
J 0
(1062 2312);
DISPLAY 0.617021 (1062 2312);
PAINT ORANGE (1062 2312);
FORCEPROP 1 LAST WATTAGE 1/16W
J 2
(1475 2200);
DISPLAY 0.617021 (1475 2200);
PAINT SKYBLUE (1475 2200);
FORCEPROP 1 LAST MATERIAL CHIP
J 0
(1000 2250);
DISPLAY 0.617021 (1000 2250);
PAINT SKYBLUE (1000 2250);
FORCEPROP 1 LAST PACK_TYPE 0402
J 0
(1350 2250);
DISPLAY 0.617021 (1350 2250);
PAINT SKYBLUE (1350 2250);
FORCEPROP 1 LAST TOLERANCE 1%
J 0
(900 2250);
DISPLAY 0.617021 (900 2250);
PAINT SKYBLUE (900 2250);
FORCEPROP 1 LAST VALUE 33.2
J 2
(850 2250);
DISPLAY 0.617021 (850 2250);
PAINT SKYBLUE (850 2250);
FORCEPROP 1 LAST PART_NUMBER G21796-074
J 0
(1100 2250);
DISPLAY 0.617021 (1100 2250);
PAINT BLUE (1100 2250);
FORCEPROP 1 LAST LOCATION R8E20
J 0
(950 2350);
DISPLAY 0.617021 (950 2350);
PAINT AQUA (950 2350);
FORCEPROP 2 LAST CDS_LIB mstr_discrete
J 0
(1000 2300);
PAINT ORANGE (1000 2300);
DISPLAY INVISIBLE (1000 2300);
FORCEPROP 2 LAST SEC_TYPE 0402
J 0
(950 2500);
DISPLAY 1.021277 (950 2500);
PAINT ORANGE (950 2500);
DISPLAY INVISIBLE (950 2500);
FORCEPROP 0 LAST BOM_COST SB
J 0
(950 2450);
DISPLAY 1.021277 (950 2450);
PAINT ORANGE (950 2450);
DISPLAY INVISIBLE (950 2450);
FORCEPROP 2 LAST SEC 1
J 0
(950 2500);
DISPLAY 0.680851 (950 2500);
PAINT MONO (950 2500);
DISPLAY INVISIBLE (950 2500);
FORCEPROP 2 LAST CDS_LOCATION R8E20
J 0
(950 2350);
DISPLAY 0.617021 (950 2350);
PAINT AQUA (950 2350);
DISPLAY INVISIBLE (950 2350);
FORCEPROP 1 LAST PATH I126
J 0
(950 2450);
DISPLAY 0.978723 (950 2450);
PAINT WHITE (950 2450);
DISPLAY INVISIBLE (950 2450);
FORCEPROP 0 LAST ROOM SB
J 0
(950 2450);
DISPLAY 1.021277 (950 2450);
PAINT ORANGE (950 2450);
DISPLAY INVISIBLE (950 2450);
FORCEADD P3V3_STBY..1
(575 1825);
FORCEPROP 3 LASTPIN (575 1775) SIG_NAME P3V3_STBY\g
J 0
(585 1785);
DISPLAY 0.659574 (585 1785);
PAINT MONO (585 1785);
DISPLAY INVISIBLE (585 1785);
FORCEPROP 1 LAST SIZE 1B
J 0
(620 1847);
DISPLAY 0.340426 (620 1847);
PAINT GREEN (620 1847);
DISPLAY INVISIBLE (620 1847);
FORCEPROP 2 LAST CDS_LIB mstr_symbols
J 0
(575 1825);
PAINT MONO (575 1825);
DISPLAY INVISIBLE (575 1825);
FORCEPROP 1 LAST BODY_TYPE PLUMBING
J 0
(530 1782);
DISPLAY 0.340426 (530 1782);
PAINT GREEN (530 1782);
DISPLAY INVISIBLE (530 1782);
FORCEPROP 1 LAST PATH I127
J 0
(620 1827);
DISPLAY 0.340426 (620 1827);
PAINT GREEN (620 1827);
DISPLAY INVISIBLE (620 1827);
FORCEPROP 1 LAST HDL_POWER P3V3_STBY
J 0
(275 1700);
DISPLAY 0.872340 (275 1700);
PAINT ORANGE (275 1700);
DISPLAY INVISIBLE (275 1700);
FORCEPROP 1 LAST VOLTAGE 3.3V
J 0
(530 1782);
DISPLAY 0.340426 (530 1782);
PAINT SKYBLUE (530 1782);
DISPLAY INVISIBLE (530 1782);
FORCEADD CAP_A..1
(575 1575);
FORCEPROP 1 LASTPIN (575 1475) $PN 2
J 0
(585 1455);
DISPLAY 0.617021 (585 1455);
PAINT ORANGE (585 1455);
FORCEPROP 1 LASTPIN (575 1675) $PN 1
J 0
(585 1655);
DISPLAY 0.617021 (585 1655);
PAINT ORANGE (585 1655);
FORCEPROP 1 LAST MATERIAL X7R
J 0
(625 1475);
DISPLAY 0.617021 (625 1475);
PAINT SKYBLUE (625 1475);
FORCEPROP 1 LAST VOLTAGE 16V
J 0
(625 1575);
DISPLAY 0.617021 (625 1575);
PAINT SKYBLUE (625 1575);
FORCEPROP 1 LAST PACK_TYPE 0402V
J 0
(625 1375);
DISPLAY 0.617021 (625 1375);
PAINT SKYBLUE (625 1375);
FORCEPROP 1 LAST TOLERANCE 10%
J 0
(625 1525);
DISPLAY 0.617021 (625 1525);
PAINT SKYBLUE (625 1525);
FORCEPROP 1 LAST VALUE 0.1UF
J 0
(625 1625);
DISPLAY 0.617021 (625 1625);
PAINT SKYBLUE (625 1625);
FORCEPROP 1 LAST PART_NUMBER A36096-030
J 0
(625 1425);
DISPLAY 0.617021 (625 1425);
PAINT BLUE (625 1425);
FORCEPROP 1 LAST LOCATION C8E8
J 0
(625 1675);
DISPLAY 0.617021 (625 1675);
PAINT AQUA (625 1675);
FORCEPROP 1 LAST PATH I128
J 0
(625 1725);
DISPLAY 0.978723 (625 1725);
PAINT WHITE (625 1725);
DISPLAY INVISIBLE (625 1725);
FORCEPROP 2 LAST CDS_LOCATION C8E8
J 0
(625 1675);
DISPLAY 0.617021 (625 1675);
PAINT AQUA (625 1675);
DISPLAY INVISIBLE (625 1675);
FORCEPROP 2 LAST BOM_COST SB
J 0
(625 1775);
DISPLAY 1.021277 (625 1775);
PAINT ORANGE (625 1775);
DISPLAY INVISIBLE (625 1775);
FORCEPROP 2 LAST CDS_LIB dev_discrete
J 0
(575 1575);
PAINT ORANGE (575 1575);
DISPLAY INVISIBLE (575 1575);
FORCEPROP 2 LAST CDS_SEC 1
J 0
(625 1725);
PAINT ORANGE (625 1725);
DISPLAY INVISIBLE (625 1725);
FORCEPROP 2 LAST SEC_TYPE 0402V
J 0
(625 1775);
DISPLAY 1.021277 (625 1775);
PAINT ORANGE (625 1775);
DISPLAY INVISIBLE (625 1775);
FORCEPROP 2 LAST SEC 1
J 0
(625 1775);
DISPLAY 0.680851 (625 1775);
PAINT MONO (625 1775);
DISPLAY INVISIBLE (625 1775);
FORCEPROP 2 LAST ROOM SB
J 0
(625 1725);
DISPLAY 1.021277 (625 1725);
PAINT ORANGE (625 1725);
DISPLAY INVISIBLE (625 1725);
FORCEADD GND..1
(575 1300);
FORCEPROP 3 LASTPIN (575 1350) SIG_NAME GND\g
J 0
(585 1360);
DISPLAY 0.659574 (585 1360);
PAINT MONO (585 1360);
DISPLAY INVISIBLE (585 1360);
FORCEPROP 1 LAST SIZE 1B
J 0
(650 1250);
DISPLAY 0.872340 (650 1250);
PAINT AQUA (650 1250);
DISPLAY INVISIBLE (650 1250);
FORCEPROP 2 LAST CDS_LIB mstr_symbols
J 0
(575 1300);
PAINT MONO (575 1300);
DISPLAY INVISIBLE (575 1300);
FORCEPROP 1 LAST BODY_TYPE PLUMBING
J 0
(530 1257);
DISPLAY 0.340426 (530 1257);
PAINT GREEN (530 1257);
DISPLAY INVISIBLE (530 1257);
FORCEPROP 1 LAST PATH I129
J 0
(650 1300);
DISPLAY 0.872340 (650 1300);
PAINT AQUA (650 1300);
DISPLAY INVISIBLE (650 1300);
FORCEPROP 1 LAST HDL_POWER GND
J 0
(575 1450);
DISPLAY 0.872340 (575 1450);
PAINT GREEN (575 1450);
DISPLAY INVISIBLE (575 1450);
FORCEPROP 1 LAST VOLTAGE 0.0V
J 0
(530 1257);
DISPLAY 0.340426 (530 1257);
PAINT SKYBLUE (530 1257);
DISPLAY INVISIBLE (530 1257);
FORCEADD TTL1G126_A..1
(0 2300);
FORCEPROP 1 LASTPIN (0 2200) $PN 1
J 0
(5 2150);
DISPLAY 0.617021 (5 2150);
PAINT WHITE (5 2150);
FORCEPROP 1 LASTPIN (-150 2300) $PN 2
J 2
(-125 2310);
DISPLAY 0.617021 (-125 2310);
PAINT WHITE (-125 2310);
FORCEPROP 1 LASTPIN (150 2300) $PN 4
J 0
(115 2310);
DISPLAY 0.617021 (115 2310);
PAINT WHITE (115 2310);
FORCEPROP 1 LAST MATERIAL IC
J 0
(-50 2450);
DISPLAY 0.617021 (-50 2450);
PAINT SKYBLUE (-50 2450);
FORCEPROP 1 LAST VALUE 74HC1G126
J 0
(-50 2400);
DISPLAY 0.617021 (-50 2400);
PAINT SKYBLUE (-50 2400);
FORCEPROP 1 LAST PART_NUMBER A79322-001
J 0
(100 2210);
DISPLAY 0.617021 (100 2210);
PAINT BLUE (100 2210);
FORCEPROP 1 LAST LOCATION U8E3
J 0
(-50 2500);
DISPLAY 0.617021 (-50 2500);
PAINT AQUA (-50 2500);
FORCEPROP 1 LAST POWER_GROUP VCC=P3V3_STBY;GND=GND;
J 0
(100 2160);
DISPLAY 0.617021 (100 2160);
PAINT ORANGE (100 2160);
FORCEPROP 2 LAST BOM_COST SB
J 0
(-50 2600);
DISPLAY 1.021277 (-50 2600);
PAINT ORANGE (-50 2600);
DISPLAY INVISIBLE (-50 2600);
FORCEPROP 2 LAST SEC_TYPE SOT
J 0
(-50 2550);
DISPLAY 1.021277 (-50 2550);
PAINT ORANGE (-50 2550);
DISPLAY INVISIBLE (-50 2550);
FORCEPROP 2 LAST CDS_LIB mstr_ttl
J 0
(0 2300);
PAINT MONO (0 2300);
DISPLAY INVISIBLE (0 2300);
FORCEPROP 2 LAST SEC 1
J 0
(-50 2550);
DISPLAY 0.680851 (-50 2550);
PAINT MONO (-50 2550);
DISPLAY INVISIBLE (-50 2550);
FORCEPROP 2 LAST CDS_LOCATION U8E3
J 0
(-50 2500);
DISPLAY 0.617021 (-50 2500);
PAINT AQUA (-50 2500);
DISPLAY INVISIBLE (-50 2500);
FORCEPROP 1 LAST PATH I130
J 2
(-105 2400);
DISPLAY 0.978723 (-105 2400);
PAINT GREEN (-105 2400);
DISPLAY INVISIBLE (-105 2400);
FORCEPROP 2 LAST ROOM SB
J 0
(-50 2550);
DISPLAY 1.021277 (-50 2550);
PAINT ORANGE (-50 2550);
DISPLAY INVISIBLE (-50 2550);
FORCEPROP 1 LAST PACK_TYPE SOT
J 0
(-50 2550);
DISPLAY 0.978723 (-50 2550);
PAINT SKYBLUE (-50 2550);
DISPLAY INVISIBLE (-50 2550);
FORCEADD P3V3_STBY..1
(-550 2100);
FORCEPROP 3 LASTPIN (-550 2050) SIG_NAME P3V3_STBY\g
J 0
(-540 2060);
DISPLAY 0.659574 (-540 2060);
PAINT MONO (-540 2060);
DISPLAY INVISIBLE (-540 2060);
FORCEPROP 1 LAST SIZE 1B
J 0
(-505 2122);
DISPLAY 0.340426 (-505 2122);
PAINT GREEN (-505 2122);
DISPLAY INVISIBLE (-505 2122);
FORCEPROP 2 LAST CDS_LIB mstr_symbols
J 0
(-550 2100);
PAINT ORANGE (-550 2100);
DISPLAY INVISIBLE (-550 2100);
FORCEPROP 1 LAST BODY_TYPE PLUMBING
J 0
(-595 2057);
DISPLAY 0.340426 (-595 2057);
PAINT GREEN (-595 2057);
DISPLAY INVISIBLE (-595 2057);
FORCEPROP 1 LAST PATH I131
J 0
(-505 2102);
DISPLAY 0.340426 (-505 2102);
PAINT GREEN (-505 2102);
DISPLAY INVISIBLE (-505 2102);
FORCEPROP 1 LAST HDL_POWER P3V3_STBY
J 0
(-850 1975);
DISPLAY 0.872340 (-850 1975);
PAINT ORANGE (-850 1975);
DISPLAY INVISIBLE (-850 1975);
FORCEPROP 1 LAST VOLTAGE 3.3V
J 0
(-595 2057);
DISPLAY 0.340426 (-595 2057);
PAINT SKYBLUE (-595 2057);
DISPLAY INVISIBLE (-595 2057);
FORCEADD OFFPAGE..1
(-650 2300);
FORCEPROP 2 LAST $XR0 120 
J 0
(-902 2300);
DISPLAY 0.638298 (-902 2300);
PAINT MONO (-902 2300);
FORCEPROP 2 LAST $XR1 136 
J 0
(-1022 2300);
DISPLAY 0.638298 (-1022 2300);
PAINT MONO (-1022 2300);
FORCEPROP 2 LAST $XR2 145 
J 0
(-1142 2300);
DISPLAY 0.638298 (-1142 2300);
PAINT MONO (-1142 2300);
FORCEPROP 2 LAST $XR3 157 
J 0
(-1262 2300);
DISPLAY 0.638298 (-1262 2300);
PAINT MONO (-1262 2300);
FORCEPROP 2 LAST PATH I132
J 0
(-900 2350);
DISPLAY 1.021277 (-900 2350);
PAINT ORANGE (-900 2350);
DISPLAY INVISIBLE (-900 2350);
FORCEPROP 1 LAST COMMENT_BODY TRUE
J 0
(-525 2200);
DISPLAY 0.872340 (-525 2200);
PAINT GREEN (-525 2200);
DISPLAY INVISIBLE (-525 2200);
FORCEPROP 1 LAST OFFPAGE TRUE
J 0
(-325 2175);
DISPLAY 0.872340 (-325 2175);
PAINT GREEN (-325 2175);
DISPLAY INVISIBLE (-325 2175);
FORCEPROP 2 LAST CDS_LIB mstr_standard
J 0
(-650 2300);
PAINT MONO (-650 2300);
DISPLAY INVISIBLE (-650 2300);
FORCEADD RES..2
(-550 1900);
FORCEPROP 1 LASTPIN (-550 1800) $PN 2
J 0
(-545 1810);
DISPLAY 0.617021 (-545 1810);
PAINT ORANGE (-545 1810);
FORCEPROP 1 LASTPIN (-550 2000) $PN 1
J 0
(-545 1962);
DISPLAY 0.617021 (-545 1962);
PAINT ORANGE (-545 1962);
FORCEPROP 1 LAST WATTAGE 1/16W
J 0
(-510 1875);
DISPLAY 0.617021 (-510 1875);
PAINT SKYBLUE (-510 1875);
FORCEPROP 1 LAST MATERIAL CHIP
J 0
(-510 1825);
DISPLAY 0.617021 (-510 1825);
PAINT SKYBLUE (-510 1825);
FORCEPROP 1 LAST PACK_TYPE 0402
J 0
(-510 1725);
DISPLAY 0.617021 (-510 1725);
PAINT SKYBLUE (-510 1725);
FORCEPROP 1 LAST TOLERANCE 1%
J 0
(-505 1925);
DISPLAY 0.617021 (-505 1925);
PAINT SKYBLUE (-505 1925);
FORCEPROP 1 LAST VALUE 4.75K
J 0
(-505 1975);
DISPLAY 0.617021 (-505 1975);
PAINT SKYBLUE (-505 1975);
FORCEPROP 1 LAST PART_NUMBER G21796-072
J 0
(-510 1775);
DISPLAY 0.617021 (-510 1775);
PAINT BLUE (-510 1775);
FORCEPROP 1 LAST LOCATION R8E14
J 0
(-505 2025);
DISPLAY 0.617021 (-505 2025);
PAINT AQUA (-505 2025);
FORCEPROP 2 LAST CDS_LIB mstr_discrete
J 0
(-550 1900);
PAINT ORANGE (-550 1900);
DISPLAY INVISIBLE (-550 1900);
FORCEPROP 2 LAST SEC_TYPE 0402
J 0
(-500 2125);
DISPLAY 1.021277 (-500 2125);
PAINT ORANGE (-500 2125);
DISPLAY INVISIBLE (-500 2125);
FORCEPROP 2 LAST SEC 1
J 0
(-500 2125);
DISPLAY 0.680851 (-500 2125);
PAINT MONO (-500 2125);
DISPLAY INVISIBLE (-500 2125);
FORCEPROP 2 LAST CDS_LOCATION R8E14
J 0
(-505 2025);
DISPLAY 0.617021 (-505 2025);
PAINT AQUA (-505 2025);
DISPLAY INVISIBLE (-505 2025);
FORCEPROP 1 LAST PATH I133
J 0
(-500 2075);
DISPLAY 0.978723 (-500 2075);
PAINT WHITE (-500 2075);
DISPLAY INVISIBLE (-500 2075);
FORCEPROP 0 LAST ROOM SB
J 0
(-500 2125);
DISPLAY 1.021277 (-500 2125);
PAINT ORANGE (-500 2125);
DISPLAY INVISIBLE (-500 2125);
FORCEADD FET_N..8
(-550 1375);
FORCEPROP 1 LASTPIN (-550 1175) $PN 2
J 2
(-492 1175);
DISPLAY 0.617021 (-492 1175);
PAINT WHITE (-492 1175);
FORCEPROP 1 LASTPIN (-750 1275) $PN 1
J 2
(-747 1290);
DISPLAY 0.617021 (-747 1290);
PAINT WHITE (-747 1290);
FORCEPROP 1 LASTPIN (-550 1575) $PN 3
J 2
(-497 1540);
DISPLAY 0.617021 (-497 1540);
PAINT WHITE (-497 1540);
FORCEPROP 1 LAST MATERIAL FET
J 0
(-350 1275);
DISPLAY 0.617021 (-350 1275);
PAINT SKYBLUE (-350 1275);
FORCEPROP 1 LAST VALUE 2N7002
J 0
(-350 1325);
DISPLAY 0.617021 (-350 1325);
PAINT SKYBLUE (-350 1325);
FORCEPROP 1 LAST PART_NUMBER C79254-001
J 0
(-350 1175);
DISPLAY 0.617021 (-350 1175);
PAINT BLUE (-350 1175);
FORCEPROP 1 LAST LOCATION Q8E1
J 0
(-350 1375);
DISPLAY 0.617021 (-350 1375);
PAINT AQUA (-350 1375);
FORCEPROP 2 LAST CDS_LIB mstr_discrete
J 0
(-550 1375);
PAINT ORANGE (-550 1375);
DISPLAY INVISIBLE (-550 1375);
FORCEPROP 2 LAST SEC_TYPE SOT23LF
J 0
(-350 1475);
DISPLAY 1.021277 (-350 1475);
PAINT ORANGE (-350 1475);
DISPLAY INVISIBLE (-350 1475);
FORCEPROP 2 LAST SEC 1
J 0
(-350 1475);
DISPLAY 0.680851 (-350 1475);
PAINT MONO (-350 1475);
DISPLAY INVISIBLE (-350 1475);
FORCEPROP 2 LAST CDS_LOCATION Q8E1
J 0
(-350 1375);
DISPLAY 0.617021 (-350 1375);
PAINT AQUA (-350 1375);
DISPLAY INVISIBLE (-350 1375);
FORCEPROP 1 LAST PATH I134
J 0
(-350 1425);
DISPLAY 0.978723 (-350 1425);
PAINT BLUE (-350 1425);
DISPLAY INVISIBLE (-350 1425);
FORCEPROP 0 LAST ROOM SB
J 0
(-350 1475);
DISPLAY 1.021277 (-350 1475);
PAINT ORANGE (-350 1475);
DISPLAY INVISIBLE (-350 1475);
FORCEPROP 1 LAST PACK_TYPE SOT23LF
J 0
(-350 1225);
DISPLAY 0.978723 (-350 1225);
PAINT SKYBLUE (-350 1225);
DISPLAY INVISIBLE (-350 1225);
FORCEADD GND..1
(-550 1075);
FORCEPROP 3 LASTPIN (-550 1125) SIG_NAME GND\g
J 0
(-540 1135);
DISPLAY 0.659574 (-540 1135);
PAINT MONO (-540 1135);
DISPLAY INVISIBLE (-540 1135);
FORCEPROP 1 LAST SIZE 1B
J 0
(-475 1025);
DISPLAY 0.872340 (-475 1025);
PAINT AQUA (-475 1025);
DISPLAY INVISIBLE (-475 1025);
FORCEPROP 2 LAST CDS_LIB mstr_symbols
J 0
(-550 1075);
PAINT ORANGE (-550 1075);
DISPLAY INVISIBLE (-550 1075);
FORCEPROP 1 LAST BODY_TYPE PLUMBING
J 0
(-595 1032);
DISPLAY 0.340426 (-595 1032);
PAINT GREEN (-595 1032);
DISPLAY INVISIBLE (-595 1032);
FORCEPROP 1 LAST PATH I135
J 0
(-475 1075);
DISPLAY 0.872340 (-475 1075);
PAINT AQUA (-475 1075);
DISPLAY INVISIBLE (-475 1075);
FORCEPROP 1 LAST HDL_POWER GND
J 0
(-550 1225);
DISPLAY 0.872340 (-550 1225);
PAINT GREEN (-550 1225);
DISPLAY INVISIBLE (-550 1225);
FORCEPROP 1 LAST VOLTAGE 0.0V
J 0
(-595 1032);
DISPLAY 0.340426 (-595 1032);
PAINT SKYBLUE (-595 1032);
DISPLAY INVISIBLE (-595 1032);
FORCEADD OFFPAGE..1
(-1225 1275);
FORCEPROP 2 LAST $XR0 119 
J 0
(-1507 1275);
DISPLAY 0.638298 (-1507 1275);
PAINT MONO (-1507 1275);
FORCEPROP 2 LAST $XR1 139 
J 0
(-1627 1275);
DISPLAY 0.638298 (-1627 1275);
PAINT MONO (-1627 1275);
FORCEPROP 2 LAST $XR2 191 
J 0
(-1747 1275);
DISPLAY 0.638298 (-1747 1275);
PAINT MONO (-1747 1275);
FORCEPROP 2 LAST PATH I136
J 0
(-1475 1325);
DISPLAY 1.021277 (-1475 1325);
PAINT ORANGE (-1475 1325);
DISPLAY INVISIBLE (-1475 1325);
FORCEPROP 1 LAST COMMENT_BODY TRUE
J 0
(-1100 1175);
DISPLAY 0.872340 (-1100 1175);
PAINT GREEN (-1100 1175);
DISPLAY INVISIBLE (-1100 1175);
FORCEPROP 1 LAST OFFPAGE TRUE
J 0
(-900 1150);
DISPLAY 0.872340 (-900 1150);
PAINT GREEN (-900 1150);
DISPLAY INVISIBLE (-900 1150);
FORCEPROP 2 LAST CDS_LIB mstr_standard
J 0
(-1225 1275);
PAINT ORANGE (-1225 1275);
DISPLAY INVISIBLE (-1225 1275);
FORCEADD RES..2
(-775 4800);
FORCEPROP 1 LASTPIN (-775 4700) $PN 2
J 0
(-770 4710);
DISPLAY 0.617021 (-770 4710);
PAINT ORANGE (-770 4710);
FORCEPROP 1 LASTPIN (-775 4900) $PN 1
J 0
(-770 4862);
DISPLAY 0.617021 (-770 4862);
PAINT ORANGE (-770 4862);
FORCEPROP 1 LAST WATTAGE 1/16W
J 0
(-735 4775);
DISPLAY 0.617021 (-735 4775);
PAINT SKYBLUE (-735 4775);
FORCEPROP 1 LAST MATERIAL CHIP
J 0
(-735 4725);
DISPLAY 0.617021 (-735 4725);
PAINT SKYBLUE (-735 4725);
FORCEPROP 1 LAST PACK_TYPE 0402
J 0
(-735 4625);
DISPLAY 0.617021 (-735 4625);
PAINT SKYBLUE (-735 4625);
FORCEPROP 1 LAST TOLERANCE 1%
J 0
(-730 4825);
DISPLAY 0.617021 (-730 4825);
PAINT SKYBLUE (-730 4825);
FORCEPROP 1 LAST VALUE 1.00K
J 0
(-730 4875);
DISPLAY 0.617021 (-730 4875);
PAINT SKYBLUE (-730 4875);
FORCEPROP 1 LAST PART_NUMBER G21796-026
J 0
(-735 4675);
DISPLAY 0.617021 (-735 4675);
PAINT BLUE (-735 4675);
FORCEPROP 1 LAST LOCATION R7G31
J 0
(-730 4925);
DISPLAY 0.617021 (-730 4925);
PAINT AQUA (-730 4925);
FORCEPROP 1 LAST PATH I139
J 0
(-725 4975);
DISPLAY 0.978723 (-725 4975);
PAINT WHITE (-725 4975);
DISPLAY INVISIBLE (-725 4975);
FORCEPROP 2 LAST SEC 1
J 0
(-725 5025);
DISPLAY 0.680851 (-725 5025);
PAINT MONO (-725 5025);
DISPLAY INVISIBLE (-725 5025);
FORCEPROP 2 LAST SEC_TYPE 0402
J 0
(-725 5025);
DISPLAY 1.021277 (-725 5025);
PAINT ORANGE (-725 5025);
DISPLAY INVISIBLE (-725 5025);
FORCEPROP 2 LAST BOM_COST SB
R 3
J 0
(-550 4750);
PAINT ORANGE (-550 4750);
DISPLAY INVISIBLE (-550 4750);
FORCEPROP 2 LAST CDS_LIB mstr_discrete
J 0
(-775 4800);
PAINT ORANGE (-775 4800);
DISPLAY INVISIBLE (-775 4800);
FORCEPROP 2 LAST ROOM SB
J 0
(-825 4625);
DISPLAY 1.361702 (-825 4625);
PAINT ORANGE (-825 4625);
DISPLAY INVISIBLE (-825 4625);
FORCEADD RES..2
(-425 3825);
FORCEPROP 1 LASTPIN (-425 3925) $PN 1
J 0
(-420 3887);
DISPLAY 0.617021 (-420 3887);
PAINT ORANGE (-420 3887);
FORCEPROP 1 LASTPIN (-425 3725) $PN 2
J 0
(-420 3735);
DISPLAY 0.617021 (-420 3735);
PAINT ORANGE (-420 3735);
FORCEPROP 1 LAST WATTAGE 1/16W
J 0
(-385 3800);
DISPLAY 0.617021 (-385 3800);
PAINT SKYBLUE (-385 3800);
FORCEPROP 1 LAST MATERIAL CHIP
J 0
(-385 3750);
DISPLAY 0.617021 (-385 3750);
PAINT SKYBLUE (-385 3750);
FORCEPROP 1 LAST PACK_TYPE 0402
J 0
(-385 3650);
DISPLAY 0.617021 (-385 3650);
PAINT SKYBLUE (-385 3650);
FORCEPROP 1 LAST TOLERANCE 1%
J 0
(-380 3850);
DISPLAY 0.617021 (-380 3850);
PAINT SKYBLUE (-380 3850);
FORCEPROP 1 LAST VALUE 20.0K
J 0
(-380 3900);
DISPLAY 0.617021 (-380 3900);
PAINT SKYBLUE (-380 3900);
FORCEPROP 1 LAST PART_NUMBER G21796-040
J 0
(-385 3700);
DISPLAY 0.617021 (-385 3700);
PAINT BLUE (-385 3700);
FORCEPROP 1 LAST LOCATION R8E16
J 0
(-380 3950);
DISPLAY 0.617021 (-380 3950);
PAINT AQUA (-380 3950);
FORCEPROP 2 LAST SEC 1
J 0
(-375 4050);
DISPLAY 0.680851 (-375 4050);
PAINT MONO (-375 4050);
DISPLAY INVISIBLE (-375 4050);
FORCEPROP 2 LAST SEC_TYPE 0402
J 0
(-375 4050);
DISPLAY 1.021277 (-375 4050);
PAINT ORANGE (-375 4050);
DISPLAY INVISIBLE (-375 4050);
FORCEPROP 2 LAST CDS_LIB mstr_discrete
J 0
(-425 3825);
PAINT ORANGE (-425 3825);
DISPLAY INVISIBLE (-425 3825);
FORCEPROP 2 LAST BOM_COST SB
R 3
J 0
(-250 3775);
PAINT ORANGE (-250 3775);
DISPLAY INVISIBLE (-250 3775);
FORCEPROP 2 LAST CDS_LOCATION R8E16
J 0
(-380 3950);
DISPLAY 0.617021 (-380 3950);
PAINT AQUA (-380 3950);
DISPLAY INVISIBLE (-380 3950);
FORCEPROP 1 LAST PATH I140
J 0
(-375 4000);
DISPLAY 0.978723 (-375 4000);
PAINT WHITE (-375 4000);
DISPLAY INVISIBLE (-375 4000);
FORCEPROP 2 LAST ROOM SB
J 0
(-380 3900);
DISPLAY 1.361702 (-380 3900);
PAINT ORANGE (-380 3900);
DISPLAY INVISIBLE (-380 3900);
FORCEADD GND..1
(-425 3625);
FORCEPROP 3 LASTPIN (-425 3675) SIG_NAME GND\g
J 0
(-415 3685);
DISPLAY 0.659574 (-415 3685);
PAINT MONO (-415 3685);
DISPLAY INVISIBLE (-415 3685);
FORCEPROP 1 LAST PATH I141
J 0
(-350 3625);
DISPLAY 0.872340 (-350 3625);
PAINT AQUA (-350 3625);
DISPLAY INVISIBLE (-350 3625);
FORCEPROP 1 LAST BODY_TYPE PLUMBING
J 0
(-470 3582);
DISPLAY 0.340426 (-470 3582);
PAINT GREEN (-470 3582);
DISPLAY INVISIBLE (-470 3582);
FORCEPROP 2 LAST BOM_COST SB
J 0
(-475 3700);
PAINT ORANGE (-475 3700);
DISPLAY INVISIBLE (-475 3700);
FORCEPROP 1 LAST SIZE 1B
J 0
(-350 3575);
DISPLAY 0.851064 (-350 3575);
PAINT GREEN (-350 3575);
DISPLAY INVISIBLE (-350 3575);
FORCEPROP 2 LAST CDS_LIB mstr_symbols
J 0
(-425 3625);
PAINT ORANGE (-425 3625);
DISPLAY INVISIBLE (-425 3625);
FORCEPROP 2 LAST ROOM WBG_HEADERS_BIOS
J 0
(-800 3700);
PAINT ORANGE (-800 3700);
DISPLAY INVISIBLE (-800 3700);
FORCEPROP 1 LAST HDL_POWER GND
J 0
(-425 3775);
DISPLAY 0.851064 (-425 3775);
PAINT GREEN (-425 3775);
DISPLAY INVISIBLE (-425 3775);
FORCEPROP 1 LAST VOLTAGE 0
J 0
(-425 3625);
PAINT SKYBLUE (-425 3625);
DISPLAY INVISIBLE (-425 3625);
FORCEADD RES..2
R 2
(-2650 4800);
FORCEPROP 1 LASTPIN (-2650 4900) $PN 1
J 2
(-2655 4862);
DISPLAY 0.617021 (-2655 4862);
PAINT ORANGE (-2655 4862);
FORCEPROP 1 LASTPIN (-2650 4700) $PN 2
J 2
(-2655 4710);
DISPLAY 0.617021 (-2655 4710);
PAINT ORANGE (-2655 4710);
FORCEPROP 1 LAST WATTAGE 1/16W
J 2
(-2690 4775);
DISPLAY 0.617021 (-2690 4775);
PAINT SKYBLUE (-2690 4775);
FORCEPROP 1 LAST MATERIAL CHIP
J 2
(-2690 4725);
DISPLAY 0.617021 (-2690 4725);
PAINT SKYBLUE (-2690 4725);
FORCEPROP 1 LAST PACK_TYPE 0402
J 2
(-2690 4625);
DISPLAY 0.617021 (-2690 4625);
PAINT SKYBLUE (-2690 4625);
FORCEPROP 1 LAST TOLERANCE 1%
J 2
(-2695 4825);
DISPLAY 0.617021 (-2695 4825);
PAINT SKYBLUE (-2695 4825);
FORCEPROP 1 LAST VALUE 10.0K
J 2
(-2695 4875);
DISPLAY 0.617021 (-2695 4875);
PAINT SKYBLUE (-2695 4875);
FORCEPROP 1 LAST PART_NUMBER G21796-016
J 2
(-2690 4675);
DISPLAY 0.617021 (-2690 4675);
PAINT BLUE (-2690 4675);
FORCEPROP 1 LAST LOCATION R2N28
J 2
(-2695 4925);
DISPLAY 0.617021 (-2695 4925);
PAINT AQUA (-2695 4925);
FORCEPROP 1 LAST PATH I147
J 2
(-2700 4975);
DISPLAY 0.978723 (-2700 4975);
PAINT WHITE (-2700 4975);
DISPLAY INVISIBLE (-2700 4975);
FORCEPROP 2 LAST SEC 1
J 2
(-2700 5025);
DISPLAY 0.680851 (-2700 5025);
PAINT MONO (-2700 5025);
DISPLAY INVISIBLE (-2700 5025);
FORCEPROP 2 LAST SEC_TYPE 0402
J 2
(-2700 5025);
DISPLAY 1.021277 (-2700 5025);
PAINT ORANGE (-2700 5025);
DISPLAY INVISIBLE (-2700 5025);
FORCEPROP 2 LAST BOM_COST SB
J 2
(-2700 4975);
PAINT ORANGE (-2700 4975);
DISPLAY INVISIBLE (-2700 4975);
FORCEPROP 2 LAST CDS_LIB mstr_discrete
J 2
(-2650 4800);
PAINT MONO (-2650 4800);
DISPLAY INVISIBLE (-2650 4800);
FORCEPROP 2 LAST ROOM SB
J 2
(-2695 4875);
DISPLAY 1.361702 (-2695 4875);
PAINT ORANGE (-2695 4875);
DISPLAY INVISIBLE (-2695 4875);
FORCEADD RES..2
(-2650 3825);
FORCEPROP 1 LASTPIN (-2650 3725) $PN 2
J 0
(-2645 3735);
DISPLAY 0.617021 (-2645 3735);
PAINT ORANGE (-2645 3735);
FORCEPROP 1 LASTPIN (-2650 3925) $PN 1
J 0
(-2645 3887);
DISPLAY 0.617021 (-2645 3887);
PAINT ORANGE (-2645 3887);
FORCEPROP 1 LAST WATTAGE 1/16W
J 0
(-2610 3800);
DISPLAY 0.617021 (-2610 3800);
PAINT SKYBLUE (-2610 3800);
FORCEPROP 1 LAST MATERIAL CHIP
J 0
(-2610 3750);
DISPLAY 0.617021 (-2610 3750);
PAINT SKYBLUE (-2610 3750);
FORCEPROP 1 LAST PACK_TYPE 0402
J 0
(-2610 3650);
DISPLAY 0.617021 (-2610 3650);
PAINT SKYBLUE (-2610 3650);
FORCEPROP 1 LAST TOLERANCE 1%
J 0
(-2605 3850);
DISPLAY 0.617021 (-2605 3850);
PAINT SKYBLUE (-2605 3850);
FORCEPROP 1 LAST VALUE 1.00K
J 0
(-2605 3900);
DISPLAY 0.617021 (-2605 3900);
PAINT SKYBLUE (-2605 3900);
FORCEPROP 1 LAST PART_NUMBER G21796-026
J 0
(-2610 3700);
DISPLAY 0.617021 (-2610 3700);
PAINT BLUE (-2610 3700);
FORCEPROP 1 LAST LOCATION R7G29
J 0
(-2605 3950);
DISPLAY 0.617021 (-2605 3950);
PAINT AQUA (-2605 3950);
FORCEPROP 1 LAST PATH I148
J 0
(-2600 4000);
DISPLAY 0.978723 (-2600 4000);
PAINT WHITE (-2600 4000);
DISPLAY INVISIBLE (-2600 4000);
FORCEPROP 2 LAST SEC 1
J 0
(-2600 4050);
DISPLAY 0.680851 (-2600 4050);
PAINT MONO (-2600 4050);
DISPLAY INVISIBLE (-2600 4050);
FORCEPROP 2 LAST SEC_TYPE 0402
J 0
(-2600 4050);
DISPLAY 1.021277 (-2600 4050);
PAINT ORANGE (-2600 4050);
DISPLAY INVISIBLE (-2600 4050);
FORCEPROP 2 LAST BOM_COST SB
R 3
J 0
(-2475 3775);
PAINT ORANGE (-2475 3775);
DISPLAY INVISIBLE (-2475 3775);
FORCEPROP 2 LAST CDS_LIB mstr_discrete
J 0
(-2650 3825);
PAINT ORANGE (-2650 3825);
DISPLAY INVISIBLE (-2650 3825);
FORCEPROP 2 LAST ROOM SB
J 0
(-2605 3900);
DISPLAY 1.361702 (-2605 3900);
PAINT ORANGE (-2605 3900);
DISPLAY INVISIBLE (-2605 3900);
FORCEADD GND..1
(-2650 3625);
FORCEPROP 3 LASTPIN (-2650 3675) SIG_NAME GND\g
J 0
(-2640 3685);
DISPLAY 0.659574 (-2640 3685);
PAINT MONO (-2640 3685);
DISPLAY INVISIBLE (-2640 3685);
FORCEPROP 1 LAST SIZE 1B
J 0
(-2575 3575);
DISPLAY 0.851064 (-2575 3575);
PAINT GREEN (-2575 3575);
DISPLAY INVISIBLE (-2575 3575);
FORCEPROP 2 LAST CDS_LIB mstr_symbols
J 0
(-2650 3625);
DISPLAY 1.148936 (-2650 3625);
PAINT ORANGE (-2650 3625);
DISPLAY INVISIBLE (-2650 3625);
FORCEPROP 2 LAST BOM_COST SB
J 0
(-2700 3700);
PAINT ORANGE (-2700 3700);
DISPLAY INVISIBLE (-2700 3700);
FORCEPROP 1 LAST BODY_TYPE PLUMBING
J 0
(-2695 3582);
DISPLAY 0.340426 (-2695 3582);
PAINT GREEN (-2695 3582);
DISPLAY INVISIBLE (-2695 3582);
FORCEPROP 1 LAST PATH I152
J 0
(-2575 3625);
DISPLAY 0.872340 (-2575 3625);
PAINT AQUA (-2575 3625);
DISPLAY INVISIBLE (-2575 3625);
FORCEPROP 2 LAST ROOM WBG_HEADERS_BIOS
J 0
(-3025 3700);
PAINT ORANGE (-3025 3700);
DISPLAY INVISIBLE (-3025 3700);
FORCEPROP 1 LAST HDL_POWER GND
J 0
(-2650 3775);
DISPLAY 0.851064 (-2650 3775);
PAINT GREEN (-2650 3775);
DISPLAY INVISIBLE (-2650 3775);
FORCEPROP 1 LAST VOLTAGE 0
J 0
(-2650 3625);
PAINT SKYBLUE (-2650 3625);
DISPLAY INVISIBLE (-2650 3625);
FORCEADD P3V3_STBY..1
(-1075 5025);
FORCEPROP 3 LASTPIN (-1075 4975) SIG_NAME P3V3_STBY\g
J 0
(-1065 4985);
DISPLAY 0.659574 (-1065 4985);
PAINT MONO (-1065 4985);
DISPLAY INVISIBLE (-1065 4985);
FORCEPROP 2 LAST CDS_LIB mstr_symbols
J 0
(-1075 5025);
PAINT MONO (-1075 5025);
DISPLAY INVISIBLE (-1075 5025);
FORCEPROP 1 LAST SIZE 1B
J 0
(-1030 5047);
DISPLAY 0.340426 (-1030 5047);
PAINT GREEN (-1030 5047);
DISPLAY INVISIBLE (-1030 5047);
FORCEPROP 1 LAST BODY_TYPE PLUMBING
J 0
(-1120 4982);
DISPLAY 0.340426 (-1120 4982);
PAINT GREEN (-1120 4982);
DISPLAY INVISIBLE (-1120 4982);
FORCEPROP 1 LAST PATH I154
J 0
(-1030 5027);
DISPLAY 0.340426 (-1030 5027);
PAINT GREEN (-1030 5027);
DISPLAY INVISIBLE (-1030 5027);
FORCEPROP 1 LAST HDL_POWER P3V3_STBY
J 0
(-1375 4900);
DISPLAY 0.872340 (-1375 4900);
PAINT ORANGE (-1375 4900);
DISPLAY INVISIBLE (-1375 4900);
FORCEPROP 1 LAST VOLTAGE 3.3V
J 0
(-1120 4982);
DISPLAY 0.340426 (-1120 4982);
PAINT SKYBLUE (-1120 4982);
DISPLAY INVISIBLE (-1120 4982);
FORCEADD RES..2
R 2
(-1075 4800);
FORCEPROP 1 LASTPIN (-1075 4700) $PN 2
J 2
(-1080 4710);
DISPLAY 0.617021 (-1080 4710);
PAINT ORANGE (-1080 4710);
FORCEPROP 1 LASTPIN (-1075 4900) $PN 1
J 2
(-1080 4862);
DISPLAY 0.617021 (-1080 4862);
PAINT ORANGE (-1080 4862);
FORCEPROP 1 LAST WATTAGE 1/16W
J 2
(-1115 4775);
DISPLAY 0.617021 (-1115 4775);
PAINT SKYBLUE (-1115 4775);
FORCEPROP 1 LAST MATERIAL CHIP
J 2
(-1115 4725);
DISPLAY 0.617021 (-1115 4725);
PAINT SKYBLUE (-1115 4725);
FORCEPROP 1 LAST PACK_TYPE 0402
J 2
(-1115 4625);
DISPLAY 0.617021 (-1115 4625);
PAINT SKYBLUE (-1115 4625);
FORCEPROP 1 LAST TOLERANCE 1%
J 2
(-1120 4825);
DISPLAY 0.617021 (-1120 4825);
PAINT SKYBLUE (-1120 4825);
FORCEPROP 1 LAST VALUE 1.00K
J 2
(-1120 4875);
DISPLAY 0.617021 (-1120 4875);
PAINT SKYBLUE (-1120 4875);
FORCEPROP 1 LAST PART_NUMBER G21796-026
J 2
(-1115 4675);
DISPLAY 0.617021 (-1115 4675);
PAINT BLUE (-1115 4675);
FORCEPROP 1 LAST LOCATION R7G27
J 2
(-1120 4925);
DISPLAY 0.617021 (-1120 4925);
PAINT AQUA (-1120 4925);
FORCEPROP 1 LAST PATH I155
J 2
(-1125 4975);
DISPLAY 0.978723 (-1125 4975);
PAINT WHITE (-1125 4975);
DISPLAY INVISIBLE (-1125 4975);
FORCEPROP 2 LAST SEC 1
J 2
(-1125 5025);
PAINT MONO (-1125 5025);
DISPLAY INVISIBLE (-1125 5025);
FORCEPROP 2 LAST CDS_LIB mstr_discrete
J 2
(-1075 4800);
PAINT MONO (-1075 4800);
DISPLAY INVISIBLE (-1075 4800);
FORCEPROP 2 LAST BOM_COST SB
J 2
(-925 4950);
PAINT ORANGE (-925 4950);
DISPLAY INVISIBLE (-925 4950);
FORCEPROP 2 LAST SEC_TYPE 0402
J 2
(-1125 5025);
DISPLAY 1.021277 (-1125 5025);
PAINT ORANGE (-1125 5025);
DISPLAY INVISIBLE (-1125 5025);
FORCEPROP 2 LAST ROOM SB
J 2
(-1650 4900);
PAINT PEACH (-1650 4900);
DISPLAY INVISIBLE (-1650 4900);
FORCEADD RES..2
(-725 3825);
FORCEPROP 1 LASTPIN (-725 3725) $PN 2
J 0
(-720 3735);
DISPLAY 0.617021 (-720 3735);
PAINT ORANGE (-720 3735);
FORCEPROP 1 LASTPIN (-725 3925) $PN 1
J 0
(-720 3887);
DISPLAY 0.617021 (-720 3887);
PAINT ORANGE (-720 3887);
FORCEPROP 1 LAST WATTAGE 1/16W
J 0
(-685 3800);
DISPLAY 0.617021 (-685 3800);
PAINT SKYBLUE (-685 3800);
FORCEPROP 1 LAST MATERIAL CHIP
J 0
(-685 3750);
DISPLAY 0.617021 (-685 3750);
PAINT SKYBLUE (-685 3750);
FORCEPROP 1 LAST PACK_TYPE 0402
J 0
(-685 3650);
DISPLAY 0.617021 (-685 3650);
PAINT SKYBLUE (-685 3650);
FORCEPROP 1 LAST TOLERANCE 1%
J 0
(-680 3850);
DISPLAY 0.617021 (-680 3850);
PAINT SKYBLUE (-680 3850);
FORCEPROP 1 LAST VALUE 10.0K
J 0
(-680 3900);
DISPLAY 0.617021 (-680 3900);
PAINT SKYBLUE (-680 3900);
FORCEPROP 1 LAST PART_NUMBER G21796-016
J 0
(-685 3700);
DISPLAY 0.617021 (-685 3700);
PAINT BLUE (-685 3700);
FORCEPROP 1 LAST LOCATION R3T14
J 0
(-680 3950);
DISPLAY 0.617021 (-680 3950);
PAINT AQUA (-680 3950);
FORCEPROP 1 LAST PATH I156
J 0
(-675 4000);
DISPLAY 0.978723 (-675 4000);
PAINT WHITE (-675 4000);
DISPLAY INVISIBLE (-675 4000);
FORCEPROP 2 LAST SEC 1
J 0
(-675 4050);
PAINT MONO (-675 4050);
DISPLAY INVISIBLE (-675 4050);
FORCEPROP 2 LAST BOM_COST SB
J 0
(-775 3675);
PAINT MONO (-775 3675);
DISPLAY INVISIBLE (-775 3675);
FORCEPROP 2 LAST CDS_LIB mstr_discrete
J 0
(-725 3825);
PAINT MONO (-725 3825);
DISPLAY INVISIBLE (-725 3825);
FORCEPROP 2 LAST SEC_TYPE 0402
J 0
(-675 4050);
DISPLAY 1.021277 (-675 4050);
PAINT ORANGE (-675 4050);
DISPLAY INVISIBLE (-675 4050);
FORCEPROP 2 LAST ROOM SB
J 0
(-725 3825);
PAINT MONO (-725 3825);
DISPLAY INVISIBLE (-725 3825);
FORCEADD GND..1
(-725 3625);
FORCEPROP 3 LASTPIN (-725 3675) SIG_NAME GND\g
J 0
(-715 3685);
DISPLAY 0.659574 (-715 3685);
PAINT MONO (-715 3685);
DISPLAY INVISIBLE (-715 3685);
FORCEPROP 1 LAST PATH I157
J 0
(-650 3625);
DISPLAY 0.872340 (-650 3625);
PAINT AQUA (-650 3625);
DISPLAY INVISIBLE (-650 3625);
FORCEPROP 1 LAST BODY_TYPE PLUMBING
J 0
(-770 3582);
DISPLAY 0.340426 (-770 3582);
PAINT GREEN (-770 3582);
DISPLAY INVISIBLE (-770 3582);
FORCEPROP 2 LAST CDS_LIB mstr_symbols
J 0
(-725 3625);
PAINT MONO (-725 3625);
DISPLAY INVISIBLE (-725 3625);
FORCEPROP 2 LAST BOM_COST SB
J 0
(-775 3700);
PAINT MONO (-775 3700);
DISPLAY INVISIBLE (-775 3700);
FORCEPROP 1 LAST SIZE 1B
J 0
(-650 3575);
DISPLAY 1.468085 (-650 3575);
PAINT GREEN (-650 3575);
DISPLAY INVISIBLE (-650 3575);
FORCEPROP 1 LAST HDL_POWER GND
J 0
(-725 3775);
DISPLAY 1.468085 (-725 3775);
PAINT GREEN (-725 3775);
DISPLAY INVISIBLE (-725 3775);
FORCEPROP 1 LAST VOLTAGE 0
J 0
(-725 3625);
PAINT SKYBLUE (-725 3625);
DISPLAY INVISIBLE (-725 3625);
FORCEADD OFFPAGE..2
(-200 4300);
FORCEPROP 2 LAST $XR0 120 
J 0
(-11 4300);
DISPLAY 0.638298 (-11 4300);
PAINT MONO (-11 4300);
FORCEPROP 2 LAST PATH I162
J 0
(-25 4375);
DISPLAY 1.021277 (-25 4375);
PAINT ORANGE (-25 4375);
DISPLAY INVISIBLE (-25 4375);
FORCEPROP 1 LAST COMMENT_BODY TRUE
J 0
(-245 4205);
DISPLAY 0.872340 (-245 4205);
PAINT GREEN (-245 4205);
DISPLAY INVISIBLE (-245 4205);
FORCEPROP 1 LAST OFFPAGE TRUE
J 0
(125 4175);
DISPLAY 0.872340 (125 4175);
PAINT GREEN (125 4175);
DISPLAY INVISIBLE (125 4175);
FORCEPROP 2 LAST CDS_LIB mstr_standard
J 0
(-200 4300);
PAINT ORANGE (-200 4300);
DISPLAY INVISIBLE (-200 4300);
FORCEADD OFFPAGE..2
(-200 4150);
FORCEPROP 2 LAST $XR0 120 
J 0
(-11 4150);
DISPLAY 0.638298 (-11 4150);
PAINT MONO (-11 4150);
FORCEPROP 2 LAST $XR1 145 
J 0
(109 4150);
DISPLAY 0.638298 (109 4150);
PAINT MONO (109 4150);
FORCEPROP 2 LAST $XR2 157 
J 0
(229 4150);
DISPLAY 0.638298 (229 4150);
PAINT MONO (229 4150);
FORCEPROP 2 LAST $XR3 136 
J 0
(349 4150);
DISPLAY 0.638298 (349 4150);
PAINT MONO (349 4150);
FORCEPROP 2 LAST PATH I165
J 0
(-25 4225);
DISPLAY 1.021277 (-25 4225);
PAINT ORANGE (-25 4225);
DISPLAY INVISIBLE (-25 4225);
FORCEPROP 1 LAST COMMENT_BODY TRUE
J 0
(-245 4055);
DISPLAY 0.872340 (-245 4055);
PAINT GREEN (-245 4055);
DISPLAY INVISIBLE (-245 4055);
FORCEPROP 1 LAST OFFPAGE TRUE
J 0
(125 4025);
DISPLAY 0.872340 (125 4025);
PAINT GREEN (125 4025);
DISPLAY INVISIBLE (125 4025);
FORCEPROP 2 LAST CDS_LIB mstr_standard
J 0
(-200 4150);
PAINT ORANGE (-200 4150);
DISPLAY INVISIBLE (-200 4150);
FORCEADD OFFPAGE..5
(-3100 4150);
FORCEPROP 2 LAST $XR0 119 
J 0
(-3355 4150);
DISPLAY 0.638298 (-3355 4150);
PAINT MONO (-3355 4150);
FORCEPROP 2 LAST CDS_LIB mstr_standard
J 0
(-3100 4150);
PAINT ORANGE (-3100 4150);
DISPLAY INVISIBLE (-3100 4150);
FORCEPROP 1 LAST OFFPAGE TRUE
J 0
(-2775 4025);
DISPLAY 0.872340 (-2775 4025);
PAINT GREEN (-2775 4025);
DISPLAY INVISIBLE (-2775 4025);
FORCEPROP 1 LAST COMMENT_BODY TRUE
J 0
(-3000 4075);
DISPLAY 0.872340 (-3000 4075);
PAINT GREEN (-3000 4075);
DISPLAY INVISIBLE (-3000 4075);
FORCEPROP 2 LAST PATH I170
J 0
(-3050 4225);
DISPLAY 1.021277 (-3050 4225);
PAINT ORANGE (-3050 4225);
DISPLAY INVISIBLE (-3050 4225);
FORCEADD CONN12_C73564003..1
(-1650 4250);
FORCEPROP 2 LASTPIN (-2000 4150) $PN 9
J 2
(-2010 4160);
DISPLAY 0.617021 (-2010 4160);
PAINT ORANGE (-2010 4160);
FORCEPROP 2 LASTPIN (-2000 4100) $PN 11
J 2
(-2010 4110);
DISPLAY 0.617021 (-2010 4110);
PAINT ORANGE (-2010 4110);
FORCEPROP 2 LASTPIN (-2000 4200) $PN 7
J 2
(-2010 4210);
DISPLAY 0.617021 (-2010 4210);
PAINT ORANGE (-2010 4210);
FORCEPROP 2 LASTPIN (-2000 4300) $PN 3
J 2
(-2010 4310);
DISPLAY 0.617021 (-2010 4310);
PAINT ORANGE (-2010 4310);
FORCEPROP 2 LASTPIN (-2000 4350) $PN 1
J 2
(-2010 4360);
DISPLAY 0.617021 (-2010 4360);
PAINT ORANGE (-2010 4360);
FORCEPROP 2 LASTPIN (-2000 4250) $PN 5
J 2
(-2010 4260);
DISPLAY 0.617021 (-2010 4260);
PAINT ORANGE (-2010 4260);
FORCEPROP 2 LASTPIN (-1300 4200) $PN 8
J 0
(-1290 4210);
DISPLAY 0.617021 (-1290 4210);
PAINT ORANGE (-1290 4210);
FORCEPROP 2 LASTPIN (-1300 4150) $PN 10
J 0
(-1290 4160);
DISPLAY 0.617021 (-1290 4160);
PAINT ORANGE (-1290 4160);
FORCEPROP 2 LASTPIN (-1300 4100) $PN 12
J 0
(-1290 4110);
DISPLAY 0.617021 (-1290 4110);
PAINT ORANGE (-1290 4110);
FORCEPROP 2 LASTPIN (-1300 4250) $PN 6
J 0
(-1290 4260);
DISPLAY 0.617021 (-1290 4260);
PAINT ORANGE (-1290 4260);
FORCEPROP 2 LASTPIN (-1300 4300) $PN 4
J 0
(-1290 4310);
DISPLAY 0.617021 (-1290 4310);
PAINT ORANGE (-1290 4310);
FORCEPROP 2 LASTPIN (-1300 4350) $PN 2
J 0
(-1290 4360);
DISPLAY 0.617021 (-1290 4360);
PAINT ORANGE (-1290 4360);
FORCEPROP 1 LAST MATERIAL CONN
J 0
(-1950 4550);
DISPLAY 0.617021 (-1950 4550);
PAINT SKYBLUE (-1950 4550);
FORCEPROP 1 LAST PART_NUMBER C73564-003
J 0
(-1950 3950);
DISPLAY 0.617021 (-1950 3950);
PAINT BLUE (-1950 3950);
FORCEPROP 1 LAST LOCATION J7G3
J 0
(-1950 4600);
DISPLAY 0.617021 (-1950 4600);
PAINT AQUA (-1950 4600);
FORCEPROP 0 LAST BOM_COST SB
J 0
(-1950 4800);
DISPLAY 1.021277 (-1950 4800);
PAINT ORANGE (-1950 4800);
DISPLAY INVISIBLE (-1950 4800);
FORCEPROP 1 LAST PATH I174
J 0
(-1650 4550);
PAINT GREEN (-1650 4550);
DISPLAY INVISIBLE (-1650 4550);
FORCEPROP 2 LAST CDS_LIB mstr_conn
J 0
(-1650 4250);
PAINT ORANGE (-1650 4250);
DISPLAY INVISIBLE (-1650 4250);
FORCEPROP 2 LAST SEC 1
J 0
(-1950 4650);
DISPLAY 0.680851 (-1950 4650);
PAINT MONO (-1950 4650);
DISPLAY INVISIBLE (-1950 4650);
FORCEPROP 2 LAST SEC_TYPE PIP
J 0
(-1950 4650);
DISPLAY 1.021277 (-1950 4650);
PAINT ORANGE (-1950 4650);
DISPLAY INVISIBLE (-1950 4650);
FORCEPROP 0 LAST ROOM SB
J 0
(-1950 4700);
DISPLAY 1.021277 (-1950 4700);
PAINT ORANGE (-1950 4700);
DISPLAY INVISIBLE (-1950 4700);
FORCEPROP 1 LAST PACK_TYPE PIP
J 0
(-1950 4650);
PAINT SKYBLUE (-1950 4650);
DISPLAY INVISIBLE (-1950 4650);
FORCEADD OFFPAGE..5
(-3100 4300);
FORCEPROP 2 LAST $XR0 119 
J 0
(-3355 4300);
DISPLAY 0.638298 (-3355 4300);
PAINT MONO (-3355 4300);
FORCEPROP 2 LAST CDS_LIB mstr_standard
J 0
(-3100 4300);
PAINT ORANGE (-3100 4300);
DISPLAY INVISIBLE (-3100 4300);
FORCEPROP 2 LAST PATH I175
J 0
(-3050 4375);
DISPLAY 1.021277 (-3050 4375);
PAINT ORANGE (-3050 4375);
DISPLAY INVISIBLE (-3050 4375);
FORCEPROP 1 LAST OFFPAGE TRUE
J 0
(-2775 4175);
DISPLAY 0.872340 (-2775 4175);
PAINT GREEN (-2775 4175);
DISPLAY INVISIBLE (-2775 4175);
FORCEPROP 1 LAST COMMENT_BODY TRUE
J 0
(-3000 4225);
DISPLAY 0.872340 (-3000 4225);
PAINT GREEN (-3000 4225);
DISPLAY INVISIBLE (-3000 4225);
FORCEADD CAD_NOTE..1
(-1800 3400);
FORCEPROP 0 LAST L1 PLACE TO THE RIGHT OF BT8G1
J 0
(-1950 3275);
DISPLAY 1.021277 (-1950 3275);
PAINT ORANGE (-1950 3275);
FORCEPROP 2 LAST CDS_LIB mstr_symbols
J 0
(-1800 3400);
PAINT ORANGE (-1800 3400);
DISPLAY INVISIBLE (-1800 3400);
FORCEPROP 1 LAST COMMENT_BODY TRUE
J 0
(-1775 3500);
DISPLAY 0.978723 (-1775 3500);
PAINT ORANGE (-1775 3500);
DISPLAY INVISIBLE (-1775 3500);
FORCEADD CAD_NOTE..1
(1000 1825);
FORCEPROP 0 LAST L1 PLACE CAP CLOSE TO VCC ON U8E3
J 0
(850 1700);
DISPLAY 1.021277 (850 1700);
PAINT ORANGE (850 1700);
FORCEPROP 2 LAST CDS_LIB mstr_symbols
J 0
(1000 1825);
PAINT MONO (1000 1825);
DISPLAY INVISIBLE (1000 1825);
FORCEPROP 1 LAST COMMENT_BODY TRUE
J 0
(1025 1925);
DISPLAY 0.978723 (1025 1925);
PAINT ORANGE (1025 1925);
DISPLAY INVISIBLE (1025 1925);
FORCEADD BOM_NOTE..1
(-4950 3125);
FORCEPROP 0 LAST L1 4 JUMPER HEADERS (IPN 634479-007) ADDED IN MOD FILE
J 0
(-5100 2975);
DISPLAY 0.808511 (-5100 2975);
PAINT ORANGE (-5100 2975);
FORCEPROP 2 LAST CDS_LIB mstr_symbols
J 0
(-4950 3125);
PAINT ORANGE (-4950 3125);
DISPLAY INVISIBLE (-4950 3125);
FORCEPROP 1 LAST COMMENT_BODY TRUE
J 0
(-4925 3225);
DISPLAY 0.978723 (-4925 3225);
PAINT ORANGE (-4925 3225);
DISPLAY INVISIBLE (-4925 3225);
FORCEADD DESIGN_NOTE..1
(-4075 5200);
FORCEPROP 0 LAST L1 ME FW UPDATE
J 0
(-4275 5075);
DISPLAY 1.021277 (-4275 5075);
PAINT ORANGE (-4275 5075);
FORCEPROP 2 LAST CDS_LIB mstr_symbols
J 0
(-4075 5200);
PAINT ORANGE (-4075 5200);
DISPLAY INVISIBLE (-4075 5200);
FORCEPROP 1 LAST COMMENT_BODY TRUE
J 0
(-4050 5300);
DISPLAY 1.361702 (-4050 5300);
PAINT WHITE (-4050 5300);
DISPLAY INVISIBLE (-4050 5300);
FORCEADD DESIGN_NOTE..1
(550 5125);
FORCEPROP 0 LAST L1 BIOS USB RECOVERY
J 0
(350 5000);
DISPLAY 1.021277 (350 5000);
PAINT ORANGE (350 5000);
FORCEPROP 2 LAST CDS_LIB mstr_symbols
J 0
(550 5125);
PAINT MONO (550 5125);
DISPLAY INVISIBLE (550 5125);
FORCEPROP 1 LAST COMMENT_BODY TRUE
J 0
(575 5225);
DISPLAY 1.361702 (575 5225);
PAINT WHITE (575 5225);
DISPLAY INVISIBLE (575 5225);
FORCEADD DESIGN_NOTE..1
(525 3375);
FORCEPROP 0 LAST L1 TOP SWAP OVERRIDE STRAP
J 0
(325 3250);
DISPLAY 1.021277 (325 3250);
PAINT ORANGE (325 3250);
FORCEPROP 2 LAST CDS_LIB mstr_symbols
J 0
(525 3375);
PAINT ORANGE (525 3375);
DISPLAY INVISIBLE (525 3375);
FORCEPROP 1 LAST COMMENT_BODY TRUE
J 0
(550 3475);
DISPLAY 0.978723 (550 3475);
PAINT ORANGE (550 3475);
DISPLAY INVISIBLE (550 3475);
FORCEADD DESIGN_NOTE..1
(525 3850);
FORCEPROP 0 LAST L1 BIOS RECOVERY MODE JUMPER
J 0
(325 3725);
DISPLAY 1.021277 (325 3725);
PAINT ORANGE (325 3725);
FORCEPROP 1 LAST COMMENT_BODY TRUE
J 0
(550 3950);
DISPLAY 1.361702 (550 3950);
PAINT WHITE (550 3950);
DISPLAY INVISIBLE (550 3950);
FORCEPROP 2 LAST CDS_LIB mstr_symbols
J 0
(525 3850);
PAINT ORANGE (525 3850);
DISPLAY INVISIBLE (525 3850);
FORCEADD DESIGN_NOTE..1
(-4050 3750);
FORCEPROP 0 LAST L1 PASSWORD CLEAR
J 0
(-4250 3625);
DISPLAY 1.021277 (-4250 3625);
PAINT ORANGE (-4250 3625);
FORCEPROP 2 LAST CDS_LIB mstr_symbols
J 0
(-4050 3750);
PAINT ORANGE (-4050 3750);
DISPLAY INVISIBLE (-4050 3750);
FORCEPROP 1 LAST COMMENT_BODY TRUE
J 0
(-4025 3850);
DISPLAY 0.978723 (-4025 3850);
PAINT ORANGE (-4025 3850);
DISPLAY INVISIBLE (-4025 3850);
FORCEADD INTEL_CORP_BPAGE..1
(2650 500);
FORCEPROP 1 LAST CDS_CON_LAST_MODIFIED Tue Dec 01 11:52:02 2015
J 0
(1225 825);
PAINT ORANGE (1225 825);
DISPLAY INVISIBLE (1225 825);
FORCEPROP 1 LAST CUSTOM_TXT_CDS <CURRENT_DESIGN_SHEET> OF <TOTAL_DESIGN_SHEETS>
J 0
(2150 525);
PAINT GREEN (2150 525);
FORCEPROP 1 LAST CUSTOM_TXT_CDS <CON_LAST_MODIFIED>
J 0
(725 850);
PAINT GREEN (725 850);
FORCEPROP 2 LAST CUSTOM_TXT_CDS <XR_PAGE_TITLE>
J 0
(-5240 5750);
DISPLAY 0.638298 (-5240 5750);
PAINT PINK (-5240 5750);
DISPLAY INVISIBLE (-5240 5750);
FORCEPROP 1 LAST SCH_TITLE LBG HEADERS (2/3)
J 0
(-5300 550);
DISPLAY 1.212766 (-5300 550);
PAINT ORANGE (-5300 550);
FORCEPROP 1 LAST SCH_ADDRESS1 2200 Mission College Blvd.
J 0
(-1325 625);
DISPLAY 0.617021 (-1325 625);
PAINT GREEN (-1325 625);
FORCEPROP 1 LAST SCH_ADDRESS2 P.O. BOX 58119
J 0
(-1325 575);
DISPLAY 0.617021 (-1325 575);
PAINT GREEN (-1325 575);
FORCEPROP 1 LAST SCH_ADDRESS3 Santa Clara, CA 95052-8119
J 0
(-1325 525);
DISPLAY 0.617021 (-1325 525);
PAINT GREEN (-1325 525);
FORCEPROP 1 LAST SCH_REV 2.420
J 0
(2400 650);
DISPLAY 0.978723 (2400 650);
PAINT YELLOW (2400 650);
FORCEPROP 1 LAST SCH_DEPT BESD
J 1
(-1800 600);
DISPLAY 1.212766 (-1800 600);
PAINT YELLOW (-1800 600);
FORCEPROP 1 LAST SCH_NUMBER H4694802
J 0
(1350 650);
DISPLAY 1.212766 (1350 650);
PAINT YELLOW (1350 650);
FORCEPROP 1 LAST COMMENT_BODY TRUE
J 0
(2662 512);
DISPLAY 0.468085 (2662 512);
PAINT GREEN (2662 512);
DISPLAY INVISIBLE (2662 512);
FORCEPROP 2 LAST BOM_COST SB
J 0
(-5225 5800);
PAINT MONO (-5225 5800);
DISPLAY INVISIBLE (-5225 5800);
FORCEPROP 2 LAST PAGE_BORDER TRUE
J 0
(-5240 5750);
DISPLAY 0.851064 (-5240 5750);
PAINT PINK (-5240 5750);
DISPLAY INVISIBLE (-5240 5750);
FORCEPROP 2 LAST CDS_LIB mstr_symbols
J 0
(2650 500);
PAINT MONO (2650 500);
DISPLAY INVISIBLE (2650 500);
FORCEPROP 2 LAST ROOM WBG_HEADERS_BIOS
J 0
(-5225 5800);
PAINT MONO (-5225 5800);
DISPLAY INVISIBLE (-5225 5800);
FORCEPROP 2 LAST CDS_XR_PAGE_TITLE CR-136 : @BASEBOARD_FAB2_LIB.BASEBOARD_FAB2(SCH_1):PAGE136
J 0
(-5240 5750);
DISPLAY 0.638298 (-5240 5750);
PAINT PINK (-5240 5750);
DISPLAY INVISIBLE (-5240 5750);
WIRE 16 -1 (-2250 3725)(-2250 3675);
WIRE 16 -1 (-2650 4900)(-2650 4950);
WIRE 16 -1 (-2650 4950)(-2250 4950);
WIRE 16 -1 (-2250 4900)(-2250 4950);
WIRE 16 -1 (-2250 4950)(-2250 4975);
WIRE 16 -1 (575 1675)(575 1775);
WIRE 16 -1 (575 1350)(575 1475);
WIRE 16 -1 (-550 2000)(-550 2050);
WIRE 16 -1 (-550 1125)(-550 1175);
WIRE 16 -1 (-425 3725)(-425 3675);
WIRE 16 -1 (-2650 3675)(-2650 3725);
WIRE 16 -1 (-775 4900)(-775 4950);
WIRE 16 -1 (-775 4950)(-1075 4950);
WIRE 16 -1 (-1075 4900)(-1075 4950);
WIRE 16 -1 (-1075 4950)(-1075 4975);
WIRE 16 -1 (-725 3725)(-725 3675);
WIRE 16 -1 (-4450 2875)(-4450 1700);
WIRE 16 -1 (-3425 1675)(-3425 2900);
WIRE 16 -1 (-5125 1675)(-3425 1675);
WIRE 16 -1 (-3425 2900)(-5125 2900);
WIRE 16 -1 (-5125 2900)(-5125 1675);
WIRE 16 -1 (-3425 3375)(-3425 3600);
WIRE 16 -1 (-4250 3375)(-3425 3375);
WIRE 16 -1 (-3425 3600)(-4250 3600);
WIRE 16 -1 (-4250 3600)(-4250 3375);
WIRE 16 -1 (-4200 3500)(-3475 3500);
WIRE 16 -1 (-5100 2750)(-3475 2750);
WIRE 16 -1 (-5100 2525)(-3475 2525);
WIRE 16 -1 (-5075 2250)(-3450 2250);
WIRE 16 -1 (-3300 4800)(-3300 5025);
WIRE 16 -1 (-4300 4800)(-3300 4800);
WIRE 16 -1 (-3300 5025)(-4300 5025);
WIRE 16 -1 (-4300 5025)(-4300 4800);
WIRE 16 -1 (-4250 4925)(-3450 4925);
WIRE 16 -1 (-5075 1975)(-3450 1975);
WIRE 16 -1 (-4025 3575)(-4025 3400);
WIRE 16 -1 (-1175 1275)(-750 1275);
FORCEPROP 2 LAST SIG_NAME RST_PLTRST_N
J 0
(-1110 1285);
DISPLAY 0.617021 (-1110 1285);
PAINT ORANGE (-1110 1285);
WIRE 16 -1 (-150 2300)(-600 2300);
FORCEPROP 2 LAST SIG_NAME FM_BIOS_TOP_SWAP
J 0
(-610 2310);
DISPLAY 0.617021 (-610 2310);
PAINT ORANGE (-610 2310);
WIRE 16 -1 (-4075 5000)(-4075 4825);
WIRE 16 -1 (-2250 3925)(-2250 4250);
FORCEPROP 2 LAST SIG_NAME PD_ME_RCVR_N
J 0
(-2410 4260);
DISPLAY 0.617021 (-2410 4260);
PAINT ORANGE (-2410 4260);
FORCEPROP 2 LASTPROP $XRERR UNIQUE?
J 0
(-2650 4260);
DISPLAY 0.638298 (-2650 4260);
PAINT MONO (-2650 4260);
DISPLAY INVISIBLE (-2650 4260);
WIRE 16 -1 (-2250 4250)(-2000 4250);
WIRE 16 -1 (-3050 4350)(-2000 4350);
FORCEPROP 2 LAST SIG_NAME TP_ME_RCVR_BOOT
J 0
(-2985 4360);
DISPLAY 0.617021 (-2985 4360);
PAINT ORANGE (-2985 4360);
FORCEPROP 2 LASTPROP $XRERR UNIQUE?
J 0
(-3290 4350);
DISPLAY 0.638298 (-3290 4350);
PAINT MONO (-3290 4350);
DISPLAY INVISIBLE (-3290 4350);
WIRE 16 -1 (-3050 4300)(-2250 4300);
WIRE 16 -1 (-2250 4300)(-2000 4300);
WIRE 16 -1 (-2250 4700)(-2250 4300);
FORCEPROP 2 LAST SIG_NAME FM_ME_RECOVER_N
J 0
(-2985 4310);
DISPLAY 0.617021 (-2985 4310);
PAINT ORANGE (-2985 4310);
WIRE 16 -1 (-3050 4200)(-2000 4200);
FORCEPROP 2 LAST SIG_NAME TP_PASSWORD_CLEAR
J 0
(-2985 4210);
DISPLAY 0.617021 (-2985 4210);
PAINT ORANGE (-2985 4210);
FORCEPROP 2 LASTPROP $XRERR UNIQUE?
J 0
(-3290 4200);
DISPLAY 0.638298 (-3290 4200);
PAINT MONO (-3290 4200);
DISPLAY INVISIBLE (-3290 4200);
WIRE 16 -1 (-2650 3925)(-2650 4100);
FORCEPROP 2 LAST SIG_NAME PD_PASSWORD_CLEAR
J 0
(-2660 4110);
DISPLAY 0.617021 (-2660 4110);
PAINT ORANGE (-2660 4110);
FORCEPROP 2 LASTPROP $XRERR UNIQUE?
J 0
(-2900 4110);
DISPLAY 0.638298 (-2900 4110);
PAINT MONO (-2900 4110);
DISPLAY INVISIBLE (-2900 4110);
WIRE 16 -1 (-2650 4100)(-2000 4100);
WIRE 16 -1 (-3050 4150)(-2650 4150);
FORCEPROP 2 LAST SIG_NAME FM_PASSWORD_CLEAR_N
J 0
(-2985 4160);
DISPLAY 0.617021 (-2985 4160);
PAINT ORANGE (-2985 4160);
WIRE 16 -1 (-2650 4150)(-2000 4150);
WIRE 16 -1 (-2650 4700)(-2650 4150);
WIRE 16 -1 (-1075 4700)(-1075 4250);
WIRE 16 -1 (-1075 4250)(-1300 4250);
FORCEPROP 2 LAST SIG_NAME PU_BIOS_USB_RECOVERY
J 0
(-1235 4260);
DISPLAY 0.617021 (-1235 4260);
PAINT ORANGE (-1235 4260);
FORCEPROP 2 LASTPROP $XRERR UNIQUE?
J 0
(-1475 4260);
DISPLAY 0.638298 (-1475 4260);
PAINT MONO (-1475 4260);
DISPLAY INVISIBLE (-1475 4260);
WIRE 16 -1 (-1300 4350)(-250 4350);
FORCEPROP 2 LAST SIG_NAME TP_BIOS_USB_RECOVERY
J 2
(-275 4360);
DISPLAY 0.617021 (-275 4360);
PAINT ORANGE (-275 4360);
FORCEPROP 2 LASTPROP $XRERR UNIQUE?
J 0
(-220 4350);
DISPLAY 0.638298 (-220 4350);
PAINT MONO (-220 4350);
DISPLAY INVISIBLE (-220 4350);
WIRE 16 -1 (-1300 4200)(-250 4200);
FORCEPROP 2 LAST SIG_NAME TP_BIOS_RECOVER_BOOT
J 2
(-275 4210);
DISPLAY 0.617021 (-275 4210);
PAINT ORANGE (-275 4210);
FORCEPROP 2 LASTPROP $XRERR UNIQUE?
J 0
(-220 4200);
DISPLAY 0.638298 (-220 4200);
PAINT MONO (-220 4200);
DISPLAY INVISIBLE (-220 4200);
WIRE 16 -1 (-775 4700)(-775 4100);
WIRE 16 -1 (-775 4100)(-1300 4100);
FORCEPROP 2 LAST SIG_NAME PU_BIOS_RECOVER_BOOT
J 0
(-1210 4110);
DISPLAY 0.617021 (-1210 4110);
PAINT ORANGE (-1210 4110);
FORCEPROP 2 LASTPROP $XRERR UNIQUE?
J 0
(-1450 4110);
DISPLAY 0.638298 (-1450 4110);
PAINT MONO (-1450 4110);
DISPLAY INVISIBLE (-1450 4110);
WIRE 16 -1 (-725 3925)(-725 4300);
WIRE 16 -1 (-725 4300)(-250 4300);
FORCEPROP 2 LAST SIG_NAME FM_BIOS_USB_RECOVERY
J 2
(-275 4310);
DISPLAY 0.617021 (-275 4310);
PAINT ORANGE (-275 4310);
WIRE 16 -1 (-1300 4300)(-725 4300);
WIRE 16 -1 (-425 3925)(-425 4150);
WIRE 16 -1 (-425 4150)(-250 4150);
FORCEPROP 2 LAST SIG_NAME FM_BIOS_TOP_SWAP
J 2
(-275 4160);
DISPLAY 0.617021 (-275 4160);
PAINT ORANGE (-275 4160);
WIRE 16 -1 (-1300 4150)(-425 4150);
WIRE 16 682 (-1950 975)(-1950 2800);
WIRE 16 682 (-1950 2800)(2575 2800);
WIRE 16 -1 (-550 1575)(-550 1625);
WIRE 16 -1 (-550 1625)(0 1625);
FORCEPROP 0 LAST SIG_NAME RST_PLTRST_TOP_SWAP
J 0
(-510 1650);
DISPLAY 0.617021 (-510 1650);
PAINT ORANGE (-510 1650);
FORCEPROP 2 LASTPROP $XRERR UNIQUE?
J 0
(-750 1650);
DISPLAY 0.638298 (-750 1650);
PAINT MONO (-750 1650);
DISPLAY INVISIBLE (-750 1650);
WIRE 16 -1 (-550 1800)(-550 1625);
WIRE 16 -1 (0 1625)(0 2200);
WIRE 16 -1 (150 2300)(900 2300);
FORCEPROP 2 LAST SIG_NAME FM_BIOS_TOP_SWAP_SPKR_R
J 0
(215 2310);
DISPLAY 0.617021 (215 2310);
PAINT ORANGE (215 2310);
FORCEPROP 2 LASTPROP $XRERR UNIQUE?
J 0
(-25 2310);
DISPLAY 0.638298 (-25 2310);
PAINT MONO (-25 2310);
DISPLAY INVISIBLE (-25 2310);
WIRE 16 -1 (375 3600)(975 3600);
WIRE 16 -1 (550 3675)(550 3500);
WIRE 16 -1 (1025 3475)(1025 3700);
WIRE 16 -1 (325 3475)(1025 3475);
WIRE 16 -1 (1025 3700)(325 3700);
WIRE 16 -1 (325 3700)(325 3475);
WIRE 16 -1 (1100 2300)(1650 2300);
FORCEPROP 0 LAST SIG_NAME FM_BIOS_TOP_SWAP_SPKR
J 0
(1140 2310);
DISPLAY 0.617021 (1140 2310);
PAINT ORANGE (1140 2310);
WIRE 16 -1 (550 4925)(550 4750);
WIRE 16 -1 (1475 4725)(1475 4950);
WIRE 16 -1 (325 4725)(1475 4725);
WIRE 16 -1 (1475 4950)(325 4950);
WIRE 16 -1 (325 4950)(325 4725);
WIRE 16 -1 (375 4850)(1450 4850);
DOT 1 (-425 4150);
DOT 1 (-2650 4150);
DOT 1 (-2250 4300);
DOT 1 (-2250 4950);
DOT 1 (-725 4300);
DOT 1 (-1075 4950);
DOT 1 (-550 1625);
FORCENOTE
4-6
(-4625 2000) 0;
DISPLAY LEFT (-4625 2000);
DISPLAY 1.021277 (-4625 2000);
PAINT PURPLE (-4625 2000);
FORCENOTE
ROOM=SB
(-5079 842) 0;
DISPLAY LEFT (-5079 842);
DISPLAY 0.617021 (-5079 842);
PAINT PURPLE (-5079 842);
FORCENOTE
10-12
(-4625 1750) 0;
DISPLAY LEFT (-4625 1750);
DISPLAY 1.021277 (-4625 1750);
PAINT PURPLE (-4625 1750);
FORCENOTE
8-10
(-4625 1875) 0;
DISPLAY LEFT (-4625 1875);
DISPLAY 1.021277 (-4625 1875);
PAINT PURPLE (-4625 1875);
FORCENOTE
JUMPER LOCATION
(-5050 2800) 0;
DISPLAY LEFT (-5050 2800);
DISPLAY 1.021277 (-5050 2800);
PAINT PURPLE (-5050 2800);
FORCENOTE
7-9
(-4625 2425) 0;
DISPLAY LEFT (-4625 2425);
DISPLAY 1.021277 (-4625 2425);
PAINT PURPLE (-4625 2425);
FORCENOTE
9-11
(-4625 2300) 0;
DISPLAY LEFT (-4625 2300);
DISPLAY 1.021277 (-4625 2300);
PAINT PURPLE (-4625 2300);
FORCENOTE
2-4
(-4625 2125) 0;
DISPLAY LEFT (-4625 2125);
DISPLAY 1.021277 (-4625 2125);
PAINT PURPLE (-4625 2125);
FORCENOTE
3-5
(-4625 2550) 0;
DISPLAY LEFT (-4625 2550);
DISPLAY 1.021277 (-4625 2550);
PAINT PURPLE (-4625 2550);
FORCENOTE
1-3
(-4625 2675) 0;
DISPLAY LEFT (-4625 2675);
DISPLAY 1.021277 (-4625 2675);
PAINT PURPLE (-4625 2675);
FORCENOTE
7-9
(-4200 3525) 0;
DISPLAY LEFT (-4200 3525);
DISPLAY 0.617021 (-4200 3525);
PAINT PURPLE (-4200 3525);
FORCENOTE
1-3
(-4250 4950) 0;
DISPLAY LEFT (-4250 4950);
DISPLAY 0.617021 (-4250 4950);
PAINT PURPLE (-4250 4950);
FORCENOTE
3-5
(-4250 4850) 0;
DISPLAY LEFT (-4250 4850);
DISPLAY 0.617021 (-4250 4850);
PAINT PURPLE (-4250 4850);
FORCENOTE
SYSTEM BEHAVIOR
(-4425 2800) 0;
DISPLAY LEFT (-4425 2800);
DISPLAY 1.021277 (-4425 2800);
PAINT PURPLE (-4425 2800);
FORCENOTE
NORMAL FUNCTIONALITY
(-4425 2675) 0;
DISPLAY LEFT (-4425 2675);
DISPLAY 1.021277 (-4425 2675);
PAINT PURPLE (-4425 2675);
FORCENOTE
BIOS USB FLASH RECVRY MODE
(-4425 2000) 0;
DISPLAY LEFT (-4425 2000);
DISPLAY 1.021277 (-4425 2000);
PAINT PURPLE (-4425 2000);
FORCENOTE
NORMAL FUNCTIONALITY
(-4425 1875) 0;
DISPLAY LEFT (-4425 1875);
DISPLAY 1.021277 (-4425 1875);
PAINT PURPLE (-4425 1875);
FORCENOTE
RECOVER BIOS
(-4425 1750) 0;
DISPLAY LEFT (-4425 1750);
DISPLAY 1.021277 (-4425 1750);
PAINT PURPLE (-4425 1750);
FORCENOTE
PASSWORD CLEAR
(-4425 2300) 0;
DISPLAY LEFT (-4425 2300);
DISPLAY 1.021277 (-4425 2300);
PAINT PURPLE (-4425 2300);
FORCENOTE
NORMAL FUNCTIONALITY
(-4425 2125) 0;
DISPLAY LEFT (-4425 2125);
DISPLAY 1.021277 (-4425 2125);
PAINT PURPLE (-4425 2125);
FORCENOTE
9-11
(-4200 3425) 0;
DISPLAY LEFT (-4200 3425);
DISPLAY 0.617021 (-4200 3425);
PAINT PURPLE (-4200 3425);
FORCENOTE
NORMAL FUNCTIONALITY
(-4425 2425) 0;
DISPLAY LEFT (-4425 2425);
DISPLAY 1.021277 (-4425 2425);
PAINT PURPLE (-4425 2425);
FORCENOTE
ME FORCE UPDATE
(-4425 2550) 0;
DISPLAY LEFT (-4425 2550);
DISPLAY 1.021277 (-4425 2550);
PAINT PURPLE (-4425 2550);
FORCENOTE
NORMAL<DEFAULT>
(-4000 3525) 0;
DISPLAY LEFT (-4000 3525);
DISPLAY 0.617021 (-4000 3525);
PAINT PURPLE (-4000 3525);
FORCENOTE
PASSWORD CLEAR
(-4000 3425) 0;
DISPLAY LEFT (-4000 3425);
DISPLAY 0.617021 (-4000 3425);
PAINT PURPLE (-4000 3425);
FORCENOTE
TOP SWAP CIRCUITRY
(-1825 2650) 0;
DISPLAY LEFT (-1825 2650);
DISPLAY 1.021277 (-1825 2650);
PAINT PURPLE (-1825 2650);
FORCENOTE
NORMAL <DEFAULT>
(-4050 4950) 0;
DISPLAY LEFT (-4050 4950);
DISPLAY 0.617021 (-4050 4950);
PAINT PURPLE (-4050 4950);
FORCENOTE
ME FORCE UPDATE
(-4050 4850) 0;
DISPLAY LEFT (-4050 4850);
DISPLAY 0.617021 (-4050 4850);
PAINT PURPLE (-4050 4850);
FORCENOTE
8-10
(375 3625) 0;
DISPLAY LEFT (375 3625);
DISPLAY 0.617021 (375 3625);
PAINT PURPLE (375 3625);
FORCENOTE
10-12
(375 3525) 0;
DISPLAY LEFT (375 3525);
DISPLAY 0.617021 (375 3525);
PAINT PURPLE (375 3525);
FORCENOTE
RECOVER BIOS
(575 3525) 0;
DISPLAY LEFT (575 3525);
DISPLAY 0.617021 (575 3525);
PAINT PURPLE (575 3525);
FORCENOTE
NORMAL<DEFAULT>
(575 3625) 0;
DISPLAY LEFT (575 3625);
DISPLAY 0.617021 (575 3625);
PAINT PURPLE (575 3625);
FORCENOTE
2-4
(375 4875) 0;
DISPLAY LEFT (375 4875);
DISPLAY 0.617021 (375 4875);
PAINT PURPLE (375 4875);
FORCENOTE
4-6
(375 4750) 0;
DISPLAY LEFT (375 4750);
DISPLAY 0.617021 (375 4750);
PAINT PURPLE (375 4750);
FORCENOTE
BIOS USB FLASH RECOVERY MODE
(600 4750) 0;
DISPLAY LEFT (600 4750);
DISPLAY 0.617021 (600 4750);
PAINT PURPLE (600 4750);
FORCENOTE
NORMAL OPERATION <DEFAULT>
(600 4875) 0;
DISPLAY LEFT (600 4875);
DISPLAY 0.617021 (600 4875);
PAINT PURPLE (600 4875);
QUIT
